# BASEBOARD_FAB2 (Tioga Pass) — schematic netlist excerpt (pin names and nets, part order shuffled) for the footprints in the layout excerpt that follows; sources: Cadence DE-HDL packaged netlist, KiCad conversion of Wiwynn_Tioga_Pass_MB.brd

C3D8  CAP_A  22.0UF 4V 20% X6S  pkg 0603V  page 76 : A = PVCCIO_CPU1 ; B = GND
R7G2  RES  0.0 5% CHIP  pkg 0402  page 215 : A = SVID_VDIO_PVDDQ_ABC ; B = SVID_DIO1_CPU0_R
C1B7  CAP  10UF 16V 10% X7R  pkg 0805  page 197 : A = P12V_NVDIMM_KLM ; B = GND

(kicad_pcb
	(version 20260206)
	(generator "pcbnew")
	(generator_version "10.0")
	(general
		(thickness 1.6)
		(legacy_teardrops no)
	)
	(paper "A4")
	(title_block
		(title "Wiwynn_Tioga_Pass_MB.brd")
		(comment 1 "Tioga Pass / footprints 1954-1956 of 4770")
	)
	(layers
		(0 "F.Cu" signal "TOP")
		(4 "In1.Cu" signal "L2GND")
		(6 "In2.Cu" signal "L3")
		(8 "In3.Cu" signal "L4GND")
		(10 "In4.Cu" signal "L5")
		(12 "In5.Cu" signal "L6GND")
		(14 "In6.Cu" signal "L7VCC")
		(16 "In7.Cu" signal "L8VCC")
		(18 "In8.Cu" signal "L9GND")
		(20 "In9.Cu" signal "L10")
		(22 "In10.Cu" signal "L11GND")
		(24 "In11.Cu" signal "L12")
		(26 "In12.Cu" signal "L13GND")
		(2 "B.Cu" signal "BOTTOM")
		(9 "F.Adhes" user "F.Adhesive")
		(11 "B.Adhes" user "B.Adhesive")
		(13 "F.Paste" user "Package Geometry/Pastemask Top")
		(15 "B.Paste" user "Package Geometry/Pastemask Bottom")
		(5 "F.SilkS" user "Ref Des/Silkscreen Top")
		(7 "B.SilkS" user "Ref Des/Silkscreen Bottom")
		(1 "F.Mask" user "Board Geometry/Soldermask Top")
		(3 "B.Mask" user "Board Geometry/Soldermask Bottom")
		(17 "Dwgs.User" user "User.Drawings")
		(19 "Cmts.User" user "User.Comments")
		(21 "Eco1.User" user "User.Eco1")
		(23 "Eco2.User" user "User.Eco2")
		(25 "Edge.Cuts" user "Board Geometry/Outline")
		(27 "Margin" user)
		(31 "F.CrtYd" user "Package Geometry/Place Bound Top")
		(29 "B.CrtYd" user "Package Geometry/Place Bound Bottom")
		(35 "F.Fab" user "Ref Des/Assembly Top")
		(33 "B.Fab" user "Ref Des/Assembly Bottom")
	)
	(footprint ""
		(layer "F.Cu")
		(at 28.380182 -130.5814 -90)
		(property "Reference" "C1B7"
			(at 0 0 270)
			(layer "F.SilkS")
			(hide yes)
			(effects
				(font
					(size 1.27 1.27)
				)
			)
		)
		(property "Value" ""
			(at 0 0 270)
			(layer "F.Fab")
			(effects
				(font
					(size 1.27 1.27)
				)
			)
		)
		(duplicate_pad_numbers_are_jumpers no)
		(fp_poly
			(pts
				(xy -0.7239 -0.2159) (xy 0.7239 -0.2159) (xy 0.7239 1.9939) (xy -0.7239 1.9939)
			)
			(stroke
				(width 0)
				(type default)
			)
			(fill no)
			(layer "F.CrtYd")
		)
		(fp_line
			(start -0.7239 1.9939)
			(end 0.7239 1.9939)
			(stroke
				(width 0.1)
				(type default)
			)
			(layer "F.Fab")
		)
		(fp_line
			(start 0.7239 1.9939)
			(end 0.7239 -0.2159)
			(stroke
				(width 0.1)
				(type default)
			)
			(layer "F.Fab")
		)
		(fp_line
			(start -0.7239 -0.2159)
			(end -0.7239 1.9939)
			(stroke
				(width 0.1)
				(type default)
			)
			(layer "F.Fab")
		)
		(fp_line
			(start 0.7239 -0.2159)
			(end -0.7239 -0.2159)
			(stroke
				(width 0.1)
				(type default)
			)
			(layer "F.Fab")
		)
		(pad "1" smd rect
			(at 0 0 270)
			(size 1.27 1.016)
			(layers "F.Cu" "F.Mask" "F.Paste")
			(net "P12V_NVDIMM_KLM")
		)
		(pad "2" smd rect
			(at 0 1.778 270)
			(size 1.27 1.016)
			(layers "F.Cu" "F.Mask" "F.Paste")
			(net "GND")
		)
		(zone
			(layer "F.Cu")
			(hatch none 0.5)
			(connect_pads
				(clearance 0)
			)
			(min_thickness 0.25)
			(keepout
				(tracks not_allowed)
				(vias allowed)
				(pads allowed)
				(copperpour not_allowed)
				(footprints allowed)
			)
			(placement
				(enabled no)
				(sheetname "")
			)
			(fill
				(thermal_gap 0.5)
				(thermal_bridge_width 0.5)
				(island_removal_mode 0)
			)
			(polygon
				(pts
					(xy 27.872182 -131.2164) (xy 27.872182 -129.9464) (xy 27.110182 -129.9464) (xy 27.110182 -131.2164)
				)
			)
		)
	)
	(footprint ""
		(layer "F.Cu")
		(at 338.836 -16.383 -90)
		(property "Reference" "R7G2"
			(at 0 0 270)
			(layer "F.SilkS")
			(hide yes)
			(effects
				(font
					(size 1.27 1.27)
				)
			)
		)
		(property "Value" ""
			(at 0 0 270)
			(layer "F.Fab")
			(effects
				(font
					(size 1.27 1.27)
				)
			)
		)
		(duplicate_pad_numbers_are_jumpers no)
		(fp_rect
			(start 0.2794 0.9906)
			(end -0.2794 -0.1016)
			(stroke
				(width 0)
				(type default)
			)
			(fill no)
			(layer "F.CrtYd")
		)
		(fp_line
			(start -0.2794 0.9906)
			(end 0.2794 0.9906)
			(stroke
				(width 0.1)
				(type default)
			)
			(layer "F.Fab")
		)
		(fp_line
			(start 0.2794 0.9906)
			(end 0.2794 -0.1016)
			(stroke
				(width 0.1)
				(type default)
			)
			(layer "F.Fab")
		)
		(fp_line
			(start -0.2794 -0.1016)
			(end -0.2794 0.9906)
			(stroke
				(width 0.1)
				(type default)
			)
			(layer "F.Fab")
		)
		(fp_line
			(start 0.2794 -0.1016)
			(end -0.2794 -0.1016)
			(stroke
				(width 0.1)
				(type default)
			)
			(layer "F.Fab")
		)
		(pad "1" smd rect
			(at 0 0 270)
			(size 0.508 0.508)
			(layers "F.Cu" "F.Mask" "F.Paste")
			(net "SVID_VDIO_PVDDQ_ABC")
		)
		(pad "2" smd rect
			(at 0 0.889 270)
			(size 0.508 0.508)
			(layers "F.Cu" "F.Mask" "F.Paste")
			(net "SVID_DIO1_CPU0_R")
		)
		(zone
			(layer "F.Cu")
			(hatch none 0.5)
			(connect_pads
				(clearance 0)
			)
			(min_thickness 0.25)
			(keepout
				(tracks not_allowed)
				(vias allowed)
				(pads allowed)
				(copperpour not_allowed)
				(footprints allowed)
			)
			(placement
				(enabled no)
				(sheetname "")
			)
			(fill
				(thermal_gap 0.5)
				(thermal_bridge_width 0.5)
				(island_removal_mode 0)
			)
			(polygon
				(pts
					(xy 338.201 -16.129) (xy 338.582 -16.129) (xy 338.582 -16.637) (xy 338.201 -16.637)
				)
			)
		)
		(zone
			(layer "F.Cu")
			(hatch none 0.5)
			(connect_pads
				(clearance 0)
			)
			(min_thickness 0.25)
			(keepout
				(tracks allowed)
				(vias not_allowed)
				(pads allowed)
				(copperpour not_allowed)
				(footprints allowed)
			)
			(placement
				(enabled no)
				(sheetname "")
			)
			(fill
				(thermal_gap 0.5)
				(thermal_bridge_width 0.5)
				(island_removal_mode 0)
			)
			(polygon
				(pts
					(xy 338.201 -16.129) (xy 338.582 -16.129) (xy 338.582 -16.637) (xy 338.201 -16.637)
				)
			)
		)
	)
	(footprint ""
		(layer "F.Cu")
		(at 113.332768 -79.6036 180)
		(property "Reference" "C3D8"
			(at 0 0 180)
			(layer "F.SilkS")
			(hide yes)
			(effects
				(font
					(size 1.27 1.27)
				)
			)
		)
		(property "Value" ""
			(at 0 0 180)
			(layer "F.Fab")
			(effects
				(font
					(size 1.27 1.27)
				)
			)
		)
		(duplicate_pad_numbers_are_jumpers no)
		(fp_poly
			(pts
				(xy -0.4953 -0.2032) (xy 0.4953 -0.2032) (xy 0.4953 1.6002) (xy -0.4953 1.6002)
			)
			(stroke
				(width 0)
				(type default)
			)
			(fill no)
			(layer "F.CrtYd")
		)
		(fp_line
			(start 0.4953 1.6002)
			(end -0.4953 1.6002)
			(stroke
				(width 0.1)
				(type default)
			)
			(layer "F.Fab")
		)
		(fp_line
			(start 0.4953 -0.2032)
			(end 0.4953 1.6002)
			(stroke
				(width 0.1)
				(type default)
			)
			(layer "F.Fab")
		)
		(fp_line
			(start -0.4953 1.6002)
			(end -0.4953 -0.2032)
			(stroke
				(width 0.1)
				(type default)
			)
			(layer "F.Fab")
		)
		(fp_line
			(start -0.4953 -0.2032)
			(end 0.4953 -0.2032)
			(stroke
				(width 0.1)
				(type default)
			)
			(layer "F.Fab")
		)
		(pad "1" smd rect
			(at 0 0 180)
			(size 0.762 0.889)
			(layers "F.Cu" "F.Mask" "F.Paste")
			(net "PVCCIO_CPU1")
		)
		(pad "2" smd rect
			(at 0 1.397 180)
			(size 0.762 0.889)
			(layers "F.Cu" "F.Mask" "F.Paste")
			(net "GND")
		)
		(zone
			(layer "F.Cu")
			(hatch none 0.5)
			(connect_pads
				(clearance 0)
			)
			(min_thickness 0.25)
			(keepout
				(tracks not_allowed)
				(vias allowed)
				(pads allowed)
				(copperpour not_allowed)
				(footprints allowed)
			)
			(placement
				(enabled no)
				(sheetname "")
			)
			(fill
				(thermal_gap 0.5)
				(thermal_bridge_width 0.5)
				(island_removal_mode 0)
			)
			(polygon
				(pts
					(xy 113.713768 -80.0481) (xy 112.951768 -80.0481) (xy 112.951768 -80.5561) (xy 113.713768 -80.5561)
				)
			)
		)
	)
)
